(kicad_pcb
	(version 20260206)
	(generator "pcbnew")
	(generator_version "10.0")
	(general
		(thickness 1.6)
		(legacy_teardrops no)
	)
	(paper "A4")
	(title_block
		(title "baseboard — 13948-1b.1110WZS1818.brd")
		(comment 1 "Honey Badger (Wiwynn) / footprints 1757-1762 of 2523")
	)
	(layers
		(0 "F.Cu" signal "TOP")
		(4 "In1.Cu" signal "L2GND")
		(6 "In2.Cu" signal "L3")
		(8 "In3.Cu" signal "L4VCC")
		(10 "In4.Cu" signal "L5VCC")
		(12 "In5.Cu" signal "L6")
		(14 "In6.Cu" signal "L7GND")
		(2 "B.Cu" signal "BOTTOM")
		(9 "F.Adhes" user "F.Adhesive")
		(11 "B.Adhes" user "B.Adhesive")
		(13 "F.Paste" user "Package Geometry/Pastemask Top")
		(15 "B.Paste" user "Package Geometry/Pastemask Bottom")
		(5 "F.SilkS" user "Ref Des/Silkscreen Top")
		(7 "B.SilkS" user "Ref Des/Silkscreen Bottom")
		(1 "F.Mask" user "Board Geometry/Soldermask Top")
		(3 "B.Mask" user "Board Geometry/Soldermask Bottom")
		(17 "Dwgs.User" user "User.Drawings")
		(19 "Cmts.User" user "User.Comments")
		(21 "Eco1.User" user "User.Eco1")
		(23 "Eco2.User" user "User.Eco2")
		(25 "Edge.Cuts" user "Board Geometry/Outline")
		(27 "Margin" user)
		(31 "F.CrtYd" user "Package Geometry/Place Bound Top")
		(29 "B.CrtYd" user "Package Geometry/Place Bound Bottom")
		(35 "F.Fab" user "Ref Des/Assembly Top")
		(33 "B.Fab" user "Ref Des/Assembly Bottom")
	)
	(footprint ""
		(layer "F.Cu")
		(at 241.9223 -118.1608 180)
		(property "Reference" "SR935"
			(at 0 0 180)
			(layer "F.SilkS")
			(hide yes)
			(effects
				(font
					(size 1.27 1.27)
				)
			)
		)
		(property "Value" "0R2J-2-GP"
			(at 0.064008 -3.993896 180)
			(unlocked yes)
			(layer "F.Fab")
			(hide yes)
			(effects
				(font
					(size 1.016 1.016)
					(thickness 0.1524)
				)
			)
		)
		(property "Device Type" "R402H16"
			(at 0.064008 -5.517896 180)
			(unlocked yes)
			(layer "F.Fab")
			(hide yes)
			(effects
				(font
					(size 1.016 1.016)
					(thickness 0.1524)
				)
			)
		)
		(duplicate_pad_numbers_are_jumpers no)
		(fp_line
			(start 0.508 -0.9398)
			(end -0.508 -0.9398)
			(stroke
				(width 0.1524)
				(type default)
			)
			(layer "F.SilkS")
		)
		(fp_line
			(start -0.508 -0.9398)
			(end -0.508 0.9398)
			(stroke
				(width 0.1524)
				(type default)
			)
			(layer "F.SilkS")
		)
		(fp_rect
			(start -0.508 0.9398)
			(end 0.508 -0.9398)
			(stroke
				(width 0)
				(type default)
			)
			(fill no)
			(layer "F.CrtYd")
		)
		(fp_rect
			(start -0.508 0.9398)
			(end 0.508 -0.9398)
			(stroke
				(width 0)
				(type default)
			)
			(fill no)
			(layer "F.Fab")
		)
		(pad "1" smd custom
			(at 0 -0.4445 180)
			(size 0.1397 0.1397)
			(layers "F.Cu" "F.Mask" "F.Paste")
			(net "SAS_SMART_R_TX")
			(options
				(clearance outline)
				(anchor circle)
			)
			(primitives
				(gr_poly
					(pts
						(arc
							(start -0.1778 -0.2794)
							(mid -0.249642 -0.249642)
							(end -0.2794 -0.1778)
						)
						(arc
							(start -0.2794 0.1778)
							(mid -0.249642 0.249642)
							(end -0.1778 0.2794)
						)
						(arc
							(start 0.1778 0.2794)
							(mid 0.249642 0.249642)
							(end 0.2794 0.1778)
						)
						(arc
							(start 0.2794 -0.1778)
							(mid 0.249642 -0.249642)
							(end 0.1778 -0.2794)
						)
					)
					(width 0)
					(fill yes)
				)
			)
		)
		(pad "2" smd custom
			(at 0 0.4445 180)
			(size 0.1397 0.1397)
			(layers "F.Cu" "F.Mask" "F.Paste")
			(net "SAS_SMART_TX")
			(options
				(clearance outline)
				(anchor circle)
			)
			(primitives
				(gr_poly
					(pts
						(arc
							(start -0.1778 -0.2794)
							(mid -0.249642 -0.249642)
							(end -0.2794 -0.1778)
						)
						(arc
							(start -0.2794 0.1778)
							(mid -0.249642 0.249642)
							(end -0.1778 0.2794)
						)
						(arc
							(start 0.1778 0.2794)
							(mid 0.249642 0.249642)
							(end 0.2794 0.1778)
						)
						(arc
							(start 0.2794 -0.1778)
							(mid 0.249642 -0.249642)
							(end 0.1778 -0.2794)
						)
					)
					(width 0)
					(fill yes)
				)
			)
		)
	)
	(footprint ""
		(layer "F.Cu")
		(at 86.976966 -80.137)
		(property "Reference" "SC1196"
			(at 0 0 0)
			(layer "F.SilkS")
			(hide yes)
			(effects
				(font
					(size 1.27 1.27)
				)
			)
		)
		(property "Value" "SC1U6D3V1MX-GP"
			(at 1.9177 2.0193 0)
			(unlocked yes)
			(layer "F.Fab")
			(hide yes)
			(effects
				(font
					(size 1.016 1.016)
					(thickness 0.1524)
				)
			)
		)
		(property "Device Type" "C0201H14"
			(at 1.9177 0.4953 0)
			(unlocked yes)
			(layer "F.Fab")
			(hide yes)
			(effects
				(font
					(size 1.016 1.016)
					(thickness 0.1524)
				)
			)
		)
		(duplicate_pad_numbers_are_jumpers no)
		(fp_rect
			(start -0.1524 0.3048)
			(end 0.1524 -0.3048)
			(stroke
				(width 0)
				(type default)
			)
			(fill no)
			(layer "F.CrtYd")
		)
		(fp_poly
			(pts
				(xy -0.2794 0.6477) (xy -0.2794 -0.6477) (xy 0.2794 -0.6477) (xy 0.2794 -0.1905) (xy 0.1524 -0.1905)
				(xy 0.1524 -0.3048) (xy -0.1524 -0.3048) (xy -0.1524 0.3048) (xy 0.1524 0.3048) (xy 0.1524 -0.1778)
				(xy 0.2794 -0.1778) (xy 0.2794 0.6477)
			)
			(stroke
				(width 0)
				(type default)
			)
			(fill no)
			(layer "F.CrtYd")
		)
		(fp_rect
			(start -0.2794 0.6477)
			(end 0.2794 -0.6477)
			(stroke
				(width 0)
				(type default)
			)
			(fill no)
			(layer "F.Fab")
		)
		(pad "1" smd custom
			(at 0 -0.2794)
			(size 0.0762 0.0762)
			(layers "F.Cu" "F.Mask" "F.Paste")
			(net "XTAL_VDDA09")
			(options
				(clearance outline)
				(anchor circle)
			)
			(primitives
				(gr_poly
					(pts
						(arc
							(start 0.1524 -0.127)
							(mid 0.137521 -0.162921)
							(end 0.1016 -0.1778)
						)
						(arc
							(start -0.1016 -0.1778)
							(mid -0.137521 -0.162921)
							(end -0.1524 -0.127)
						)
						(arc
							(start -0.1524 0.127)
							(mid -0.137521 0.162921)
							(end -0.1016 0.1778)
						)
						(arc
							(start 0.1016 0.1778)
							(mid 0.137521 0.162921)
							(end 0.1524 0.127)
						)
					)
					(width 0)
					(fill yes)
				)
			)
		)
		(pad "2" smd custom
			(at 0 0.2794)
			(size 0.0762 0.0762)
			(layers "F.Cu" "F.Mask" "F.Paste")
			(net "GND")
			(options
				(clearance outline)
				(anchor circle)
			)
			(primitives
				(gr_poly
					(pts
						(arc
							(start 0.1524 -0.127)
							(mid 0.137521 -0.162921)
							(end 0.1016 -0.1778)
						)
						(arc
							(start -0.1016 -0.1778)
							(mid -0.137521 -0.162921)
							(end -0.1524 -0.127)
						)
						(arc
							(start -0.1524 0.127)
							(mid -0.137521 0.162921)
							(end -0.1016 0.1778)
						)
						(arc
							(start 0.1016 0.1778)
							(mid 0.137521 0.162921)
							(end 0.1524 0.127)
						)
					)
					(width 0)
					(fill yes)
				)
			)
		)
	)
	(footprint ""
		(layer "F.Cu")
		(at 333.912718 -150.091648 90)
		(property "Reference" "R548"
			(at 0 0 90)
			(layer "F.SilkS")
			(hide yes)
			(effects
				(font
					(size 1.27 1.27)
				)
			)
		)
		(property "Value" "4K7R2F-GP"
			(at 0.064008 -3.993896 90)
			(unlocked yes)
			(layer "F.Fab")
			(hide yes)
			(effects
				(font
					(size 1.016 1.016)
					(thickness 0.1524)
				)
			)
		)
		(property "Device Type" "R402H16"
			(at 0.064008 -5.517896 90)
			(unlocked yes)
			(layer "F.Fab")
			(hide yes)
			(effects
				(font
					(size 1.016 1.016)
					(thickness 0.1524)
				)
			)
		)
		(duplicate_pad_numbers_are_jumpers no)
		(fp_line
			(start 0.508 -0.9398)
			(end -0.508 -0.9398)
			(stroke
				(width 0.1524)
				(type default)
			)
			(layer "F.SilkS")
		)
		(fp_line
			(start -0.508 -0.9398)
			(end -0.508 0.9398)
			(stroke
				(width 0.1524)
				(type default)
			)
			(layer "F.SilkS")
		)
		(fp_rect
			(start -0.508 0.9398)
			(end 0.508 -0.9398)
			(stroke
				(width 0)
				(type default)
			)
			(fill no)
			(layer "F.CrtYd")
		)
		(fp_rect
			(start -0.508 0.9398)
			(end 0.508 -0.9398)
			(stroke
				(width 0)
				(type default)
			)
			(fill no)
			(layer "F.Fab")
		)
		(pad "1" smd custom
			(at 0 -0.4445 90)
			(size 0.1397 0.1397)
			(layers "F.Cu" "F.Mask" "F.Paste")
			(net "P3V3_STBY")
			(options
				(clearance outline)
				(anchor circle)
			)
			(primitives
				(gr_poly
					(pts
						(arc
							(start -0.1778 -0.2794)
							(mid -0.249642 -0.249642)
							(end -0.2794 -0.1778)
						)
						(arc
							(start -0.2794 0.1778)
							(mid -0.249642 0.249642)
							(end -0.1778 0.2794)
						)
						(arc
							(start 0.1778 0.2794)
							(mid 0.249642 0.249642)
							(end 0.2794 0.1778)
						)
						(arc
							(start 0.2794 -0.1778)
							(mid 0.249642 -0.249642)
							(end 0.1778 -0.2794)
						)
					)
					(width 0)
					(fill yes)
				)
			)
		)
		(pad "2" smd custom
			(at 0 0.4445 90)
			(size 0.1397 0.1397)
			(layers "F.Cu" "F.Mask" "F.Paste")
			(net "CFG_SEL0")
			(options
				(clearance outline)
				(anchor circle)
			)
			(primitives
				(gr_poly
					(pts
						(arc
							(start -0.1778 -0.2794)
							(mid -0.249642 -0.249642)
							(end -0.2794 -0.1778)
						)
						(arc
							(start -0.2794 0.1778)
							(mid -0.249642 0.249642)
							(end -0.1778 0.2794)
						)
						(arc
							(start 0.1778 0.2794)
							(mid 0.249642 0.249642)
							(end 0.2794 0.1778)
						)
						(arc
							(start 0.2794 -0.1778)
							(mid 0.249642 -0.249642)
							(end 0.1778 -0.2794)
						)
					)
					(width 0)
					(fill yes)
				)
			)
		)
	)
	(footprint ""
		(layer "F.Cu")
		(at 261.874 -37.338 180)
		(property "Reference" "PR53"
			(at 0 0 180)
			(layer "F.SilkS")
			(hide yes)
			(effects
				(font
					(size 1.27 1.27)
				)
			)
		)
		(property "Value" "20KR2F-L-GP"
			(at 0.064008 -3.993896 180)
			(unlocked yes)
			(layer "F.Fab")
			(hide yes)
			(effects
				(font
					(size 1.016 1.016)
					(thickness 0.1524)
				)
			)
		)
		(property "Device Type" "R402H16"
			(at 0.064008 -5.517896 180)
			(unlocked yes)
			(layer "F.Fab")
			(hide yes)
			(effects
				(font
					(size 1.016 1.016)
					(thickness 0.1524)
				)
			)
		)
		(duplicate_pad_numbers_are_jumpers no)
		(fp_line
			(start 0.508 -0.9398)
			(end -0.508 -0.9398)
			(stroke
				(width 0.1524)
				(type default)
			)
			(layer "F.SilkS")
		)
		(fp_line
			(start -0.508 -0.9398)
			(end -0.508 0.9398)
			(stroke
				(width 0.1524)
				(type default)
			)
			(layer "F.SilkS")
		)
		(fp_rect
			(start -0.508 0.9398)
			(end 0.508 -0.9398)
			(stroke
				(width 0)
				(type default)
			)
			(fill no)
			(layer "F.CrtYd")
		)
		(fp_rect
			(start -0.508 0.9398)
			(end 0.508 -0.9398)
			(stroke
				(width 0)
				(type default)
			)
			(fill no)
			(layer "F.Fab")
		)
		(pad "1" smd custom
			(at 0 -0.4445 180)
			(size 0.1397 0.1397)
			(layers "F.Cu" "F.Mask" "F.Paste")
			(net "P1V8_STBY_VFB")
			(options
				(clearance outline)
				(anchor circle)
			)
			(primitives
				(gr_poly
					(pts
						(arc
							(start -0.1778 -0.2794)
							(mid -0.249642 -0.249642)
							(end -0.2794 -0.1778)
						)
						(arc
							(start -0.2794 0.1778)
							(mid -0.249642 0.249642)
							(end -0.1778 0.2794)
						)
						(arc
							(start 0.1778 0.2794)
							(mid 0.249642 0.249642)
							(end 0.2794 0.1778)
						)
						(arc
							(start 0.2794 -0.1778)
							(mid 0.249642 -0.249642)
							(end 0.1778 -0.2794)
						)
					)
					(width 0)
					(fill yes)
				)
			)
		)
		(pad "2" smd custom
			(at 0 0.4445 180)
			(size 0.1397 0.1397)
			(layers "F.Cu" "F.Mask" "F.Paste")
			(net "P1V8_STBY_VFB_R")
			(options
				(clearance outline)
				(anchor circle)
			)
			(primitives
				(gr_poly
					(pts
						(arc
							(start -0.1778 -0.2794)
							(mid -0.249642 -0.249642)
							(end -0.2794 -0.1778)
						)
						(arc
							(start -0.2794 0.1778)
							(mid -0.249642 0.249642)
							(end -0.1778 0.2794)
						)
						(arc
							(start 0.1778 0.2794)
							(mid 0.249642 0.249642)
							(end 0.2794 0.1778)
						)
						(arc
							(start 0.2794 -0.1778)
							(mid 0.249642 -0.249642)
							(end 0.1778 -0.2794)
						)
					)
					(width 0)
					(fill yes)
				)
			)
		)
	)
	(footprint ""
		(layer "F.Cu")
		(at 193.416936 -141.221714 90)
		(property "Reference" "SU67"
			(at 0 0 90)
			(layer "F.SilkS")
			(hide yes)
			(effects
				(font
					(size 1.27 1.27)
				)
			)
		)
		(property "Value" "AT24C64D-SSHM-T-GP"
			(at -3.707384 -1.5367 90)
			(unlocked yes)
			(layer "F.Fab")
			(hide yes)
			(effects
				(font
					(size 1.016 1.016)
					(thickness 0.1524)
				)
			)
		)
		(property "Device Type" "SOIC8H69"
			(at -3.707384 -3.0607 90)
			(unlocked yes)
			(layer "F.Fab")
			(hide yes)
			(effects
				(font
					(size 1.016 1.016)
					(thickness 0.1524)
				)
			)
		)
		(duplicate_pad_numbers_are_jumpers no)
		(fp_line
			(start 2.1336 -1.4224)
			(end -2.7432 -1.4224)
			(stroke
				(width 0.1524)
				(type default)
			)
			(layer "F.SilkS")
		)
		(fp_line
			(start -2.7432 -1.4224)
			(end -2.7432 1.4224)
			(stroke
				(width 0.1524)
				(type default)
			)
			(layer "F.SilkS")
		)
		(fp_line
			(start -2.7178 -0.508)
			(end -2.1844 -0.0508)
			(stroke
				(width 0.1524)
				(type default)
			)
			(layer "F.SilkS")
		)
		(fp_line
			(start -2.1844 -0.0508)
			(end -2.7178 0.508)
			(stroke
				(width 0.1524)
				(type default)
			)
			(layer "F.SilkS")
		)
		(fp_line
			(start 2.1336 1.4224)
			(end 2.1336 -1.4224)
			(stroke
				(width 0.1524)
				(type default)
			)
			(layer "F.SilkS")
		)
		(fp_line
			(start -2.7432 1.4224)
			(end 2.1336 1.4224)
			(stroke
				(width 0.1524)
				(type default)
			)
			(layer "F.SilkS")
		)
		(fp_line
			(start -2.7432 1.4224)
			(end -2.6416 1.4224)
			(stroke
				(width 0.1524)
				(type default)
			)
			(layer "F.SilkS")
		)
		(fp_line
			(start -2.6289 3.4417)
			(end -2.6289 1.4732)
			(stroke
				(width 0.381)
				(type default)
			)
			(layer "F.SilkS")
		)
		(fp_poly
			(pts
				(xy -2.2098 -1.4224) (xy -2.2098 1.4224) (xy 2.2098 1.4224) (xy 2.2098 -1.4224)
			)
			(stroke
				(width 0)
				(type default)
			)
			(fill yes)
			(layer "F.SilkS")
		)
		(fp_rect
			(start -2.450084 2.999994)
			(end 2.450084 -2.999994)
			(stroke
				(width 0)
				(type default)
			)
			(fill no)
			(layer "F.CrtYd")
		)
		(fp_poly
			(pts
				(xy -2.8194 3.6322) (xy -2.8194 -3.6322) (xy 2.8194 -3.6322) (xy 2.8194 1.18364) (xy 2.450084 1.18364)
				(xy 2.450084 -2.999994) (xy -2.450084 -2.999994) (xy -2.450084 2.999994) (xy 2.450084 2.999994)
				(xy 2.450084 1.18618) (xy 2.8194 1.18618) (xy 2.8194 3.6322)
			)
			(stroke
				(width 0)
				(type default)
			)
			(fill no)
			(layer "F.CrtYd")
		)
		(fp_rect
			(start -2.8194 3.6322)
			(end 2.8194 -3.6322)
			(stroke
				(width 0)
				(type default)
			)
			(fill no)
			(layer "F.Fab")
		)
		(pad "1" smd rect
			(at -1.905 2.54 90)
			(size 0.635 1.651)
			(layers "F.Cu" "F.Mask" "F.Paste")
			(net "EXP_EEPROM_A0")
		)
		(pad "2" smd rect
			(at -0.635 2.54 90)
			(size 0.635 1.651)
			(layers "F.Cu" "F.Mask" "F.Paste")
			(net "EXP_EEPROM_A1")
		)
		(pad "3" smd rect
			(at 0.635 2.54 90)
			(size 0.635 1.651)
			(layers "F.Cu" "F.Mask" "F.Paste")
			(net "EXP_EEPROM_A2")
		)
		(pad "4" smd rect
			(at 1.905 2.54 90)
			(size 0.635 1.651)
			(layers "F.Cu" "F.Mask" "F.Paste")
			(net "GND")
		)
		(pad "5" smd rect
			(at 1.905 -2.54 90)
			(size 0.635 1.651)
			(layers "F.Cu" "F.Mask" "F.Paste")
			(net "EXP_EEPROM_SDA")
		)
		(pad "6" smd rect
			(at 0.635 -2.54 90)
			(size 0.635 1.651)
			(layers "F.Cu" "F.Mask" "F.Paste")
			(net "EXP_EEPROM_SCL")
		)
		(pad "7" smd rect
			(at -0.635 -2.54 90)
			(size 0.635 1.651)
			(layers "F.Cu" "F.Mask" "F.Paste")
			(net "EXP_EEPROM_WP")
		)
		(pad "8" smd rect
			(at -1.905 -2.54 90)
			(size 0.635 1.651)
			(layers "F.Cu" "F.Mask" "F.Paste")
			(net "P1V8_E")
		)
	)
	(footprint ""
		(layer "F.Cu")
		(at 346.858336 -76.538328 180)
		(property "Reference" "U19"
			(at 0 0 180)
			(layer "F.SilkS")
			(hide yes)
			(effects
				(font
					(size 1.27 1.27)
				)
			)
		)
		(property "Value" "MX25L25635FMI-10G-GP"
			(at 0 -14.6812 180)
			(unlocked yes)
			(layer "F.Fab")
			(hide yes)
			(effects
				(font
					(size 1.016 1.016)
					(thickness 0.1524)
				)
			)
		)
		(property "Device Type" "SOIC16-6H105"
			(at 0 -16.2052 180)
			(unlocked yes)
			(layer "F.Fab")
			(hide yes)
			(effects
				(font
					(size 1.016 1.016)
					(thickness 0.1524)
				)
			)
		)
		(duplicate_pad_numbers_are_jumpers no)
		(fp_line
			(start 4.7498 3.2258)
			(end -5.588 3.2258)
			(stroke
				(width 0.1524)
				(type default)
			)
			(layer "F.SilkS")
		)
		(fp_line
			(start 4.7498 -3.2258)
			(end 4.7498 3.2258)
			(stroke
				(width 0.1524)
				(type default)
			)
			(layer "F.SilkS")
		)
		(fp_line
			(start -5.08762 0)
			(end -5.588 0.50038)
			(stroke
				(width 0.1524)
				(type default)
			)
			(layer "F.SilkS")
		)
		(fp_line
			(start -5.4102 3.2258)
			(end -5.4102 5.7912)
			(stroke
				(width 0.508)
				(type default)
			)
			(layer "F.SilkS")
		)
		(fp_line
			(start -5.588 3.2258)
			(end -5.588 -3.2258)
			(stroke
				(width 0.1524)
				(type default)
			)
			(layer "F.SilkS")
		)
		(fp_line
			(start -5.588 -0.50038)
			(end -5.08762 0)
			(stroke
				(width 0.1524)
				(type default)
			)
			(layer "F.SilkS")
		)
		(fp_line
			(start -5.588 -3.2258)
			(end 4.7498 -3.2258)
			(stroke
				(width 0.1524)
				(type default)
			)
			(layer "F.SilkS")
		)
		(fp_poly
			(pts
				(xy -4.764786 -3.2258) (xy 4.7625 -3.2258) (xy 4.7625 3.2258) (xy -4.764786 3.2258)
			)
			(stroke
				(width 0)
				(type default)
			)
			(fill yes)
			(layer "F.SilkS")
		)
		(fp_poly
			(pts
				(xy -5.6642 6.0452) (xy 5.6642 6.0452) (xy 5.6642 -6.0452) (xy -5.6642 -6.0452)
			)
			(stroke
				(width 0)
				(type default)
			)
			(fill no)
			(layer "F.CrtYd")
		)
		(fp_poly
			(pts
				(xy -5.6642 -6.0452) (xy 5.6642 -6.0452) (xy 5.6642 6.0452) (xy -5.6642 6.0452)
			)
			(stroke
				(width 0)
				(type default)
			)
			(fill no)
			(layer "F.Fab")
		)
		(pad "1" smd rect
			(at -4.445 4.71805 180)
			(size 0.635 1.651)
			(layers "F.Cu" "F.Mask" "F.Paste")
			(net "PU_IBMC_BT_HOLD_N")
		)
		(pad "2" smd rect
			(at -3.175 4.71805 180)
			(size 0.635 1.651)
			(layers "F.Cu" "F.Mask" "F.Paste")
			(net "P3V3_STBY")
		)
		(pad "3" smd rect
			(at -1.905 4.71805 180)
			(size 0.635 1.651)
			(layers "F.Cu" "F.Mask" "F.Paste")
			(net "Net_2083")
		)
		(pad "4" smd rect
			(at -0.635 4.71805 180)
			(size 0.635 1.651)
			(layers "F.Cu" "F.Mask" "F.Paste")
			(net "Net_2082")
		)
		(pad "5" smd rect
			(at 0.635 4.71805 180)
			(size 0.635 1.651)
			(layers "F.Cu" "F.Mask" "F.Paste")
			(net "Net_2081")
		)
		(pad "6" smd rect
			(at 1.905 4.71805 180)
			(size 0.635 1.651)
			(layers "F.Cu" "F.Mask" "F.Paste")
			(net "Net_2080")
		)
		(pad "7" smd rect
			(at 3.175 4.71805 180)
			(size 0.635 1.651)
			(layers "F.Cu" "F.Mask" "F.Paste")
			(net "FLA_CS_R")
		)
		(pad "8" smd rect
			(at 4.445 4.71805 180)
			(size 0.635 1.651)
			(layers "F.Cu" "F.Mask" "F.Paste")
			(net "ROMD2_R")
		)
		(pad "9" smd rect
			(at 4.445 -4.71805 180)
			(size 0.635 1.651)
			(layers "F.Cu" "F.Mask" "F.Paste")
			(net "FLA_WPN")
		)
		(pad "10" smd rect
			(at 3.175 -4.71805 180)
			(size 0.635 1.651)
			(layers "F.Cu" "F.Mask" "F.Paste")
			(net "GND")
		)
		(pad "11" smd rect
			(at 1.905 -4.71805 180)
			(size 0.635 1.651)
			(layers "F.Cu" "F.Mask" "F.Paste")
			(net "Net_2079")
		)
		(pad "12" smd rect
			(at 0.635 -4.71805 180)
			(size 0.635 1.651)
			(layers "F.Cu" "F.Mask" "F.Paste")
			(net "Net_2078")
		)
		(pad "13" smd rect
			(at -0.635 -4.71805 180)
			(size 0.635 1.651)
			(layers "F.Cu" "F.Mask" "F.Paste")
			(net "Net_2077")
		)
		(pad "14" smd rect
			(at -1.905 -4.71805 180)
			(size 0.635 1.651)
			(layers "F.Cu" "F.Mask" "F.Paste")
			(net "Net_2076")
		)
		(pad "15" smd rect
			(at -3.175 -4.71805 180)
			(size 0.635 1.651)
			(layers "F.Cu" "F.Mask" "F.Paste")
			(net "ROMD1_R")
		)
		(pad "16" smd rect
			(at -4.445 -4.71805 180)
			(size 0.635 1.651)
			(layers "F.Cu" "F.Mask" "F.Paste")
			(net "ROMD0_R")
		)
	)
)
